# BASEBOARD_FAB2 (Tioga Pass) — schematic netlist excerpt (pin names and nets, part order shuffled) for the footprints in the layout excerpt that follows; sources: Cadence DE-HDL packaged netlist, KiCad conversion of Wiwynn_Tioga_Pass_MB.brd

C25W5  CAP  1.0UF 16V 10% X6S  pkg 0402  page 151 : A = P1V2_AUX_BMC ; B = GND
R9U8  RES  100.0K 1% EMPTY  pkg 0402  page 223 : A = P3V3_STBY ; B = VR_PVDDQ_GHJ_VREN
R9N14  RES  1.00K 1% CHIP  pkg 0402  page 206 : A = PVCCIO_CPU1 ; B = VR_PVCCIN_CPU1_VREN

(kicad_pcb
	(version 20260206)
	(generator "pcbnew")
	(generator_version "10.0")
	(general
		(thickness 1.6)
		(legacy_teardrops no)
	)
	(paper "A4")
	(title_block
		(title "Wiwynn_Tioga_Pass_MB.brd")
		(comment 1 "Tioga Pass / footprints 4232-4234 of 4770")
	)
	(layers
		(0 "F.Cu" signal "TOP")
		(4 "In1.Cu" signal "L2GND")
		(6 "In2.Cu" signal "L3")
		(8 "In3.Cu" signal "L4GND")
		(10 "In4.Cu" signal "L5")
		(12 "In5.Cu" signal "L6GND")
		(14 "In6.Cu" signal "L7VCC")
		(16 "In7.Cu" signal "L8VCC")
		(18 "In8.Cu" signal "L9GND")
		(20 "In9.Cu" signal "L10")
		(22 "In10.Cu" signal "L11GND")
		(24 "In11.Cu" signal "L12")
		(26 "In12.Cu" signal "L13GND")
		(2 "B.Cu" signal "BOTTOM")
		(9 "F.Adhes" user "F.Adhesive")
		(11 "B.Adhes" user "B.Adhesive")
		(13 "F.Paste" user "Package Geometry/Pastemask Top")
		(15 "B.Paste" user "Package Geometry/Pastemask Bottom")
		(5 "F.SilkS" user "Ref Des/Silkscreen Top")
		(7 "B.SilkS" user "Ref Des/Silkscreen Bottom")
		(1 "F.Mask" user "Board Geometry/Soldermask Top")
		(3 "B.Mask" user "Board Geometry/Soldermask Bottom")
		(17 "Dwgs.User" user "User.Drawings")
		(19 "Cmts.User" user "User.Comments")
		(21 "Eco1.User" user "User.Eco1")
		(23 "Eco2.User" user "User.Eco2")
		(25 "Edge.Cuts" user "Board Geometry/Outline")
		(27 "Margin" user)
		(31 "F.CrtYd" user "Package Geometry/Place Bound Top")
		(29 "B.CrtYd" user "Package Geometry/Place Bound Bottom")
		(35 "F.Fab" user "Ref Des/Assembly Top")
		(33 "B.Fab" user "Ref Des/Assembly Bottom")
	)
	(footprint ""
		(layer "B.Cu")
		(at 17.399 -89.281 -90)
		(property "Reference" "R9N14"
			(at 0 0 90)
			(layer "B.SilkS")
			(hide yes)
			(effects
				(font
					(size 1.27 1.27)
				)
				(justify mirror)
			)
		)
		(property "Value" ""
			(at 0 0 90)
			(layer "B.Fab")
			(effects
				(font
					(size 1.27 1.27)
				)
				(justify mirror)
			)
		)
		(duplicate_pad_numbers_are_jumpers no)
		(fp_poly
			(pts
				(xy 0.2794 -0.1016) (xy -0.2794 -0.1016) (xy -0.2794 0.9906) (xy 0.2794 0.9906)
			)
			(stroke
				(width 0)
				(type default)
			)
			(fill no)
			(layer "B.CrtYd")
		)
		(fp_line
			(start -0.2794 0.9906)
			(end -0.2794 -0.1016)
			(stroke
				(width 0.1)
				(type default)
			)
			(layer "B.Fab")
		)
		(fp_line
			(start 0.2794 0.9906)
			(end -0.2794 0.9906)
			(stroke
				(width 0.1)
				(type default)
			)
			(layer "B.Fab")
		)
		(fp_line
			(start -0.2794 -0.1016)
			(end 0.2794 -0.1016)
			(stroke
				(width 0.1)
				(type default)
			)
			(layer "B.Fab")
		)
		(fp_line
			(start 0.2794 -0.1016)
			(end 0.2794 0.9906)
			(stroke
				(width 0.1)
				(type default)
			)
			(layer "B.Fab")
		)
		(pad "1" smd rect
			(at 0 0 90)
			(size 0.508 0.508)
			(layers "B.Cu" "B.Mask" "B.Paste")
			(net "PVCCIO_CPU1")
		)
		(pad "2" smd rect
			(at 0 0.889 90)
			(size 0.508 0.508)
			(layers "B.Cu" "B.Mask" "B.Paste")
			(net "VR_PVCCIN_CPU1_VREN")
		)
		(zone
			(layer "B.Cu")
			(hatch none 0.5)
			(connect_pads
				(clearance 0)
			)
			(min_thickness 0.25)
			(keepout
				(tracks not_allowed)
				(vias allowed)
				(pads allowed)
				(copperpour not_allowed)
				(footprints allowed)
			)
			(placement
				(enabled no)
				(sheetname "")
			)
			(fill
				(thermal_gap 0.5)
				(thermal_bridge_width 0.5)
				(island_removal_mode 0)
			)
			(polygon
				(pts
					(xy 16.764 -89.027) (xy 16.764 -89.535) (xy 17.145 -89.535) (xy 17.145 -89.027)
				)
			)
		)
		(zone
			(layer "B.Cu")
			(hatch none 0.5)
			(connect_pads
				(clearance 0)
			)
			(min_thickness 0.25)
			(keepout
				(tracks allowed)
				(vias not_allowed)
				(pads allowed)
				(copperpour not_allowed)
				(footprints allowed)
			)
			(placement
				(enabled no)
				(sheetname "")
			)
			(fill
				(thermal_gap 0.5)
				(thermal_bridge_width 0.5)
				(island_removal_mode 0)
			)
			(polygon
				(pts
					(xy 17.145 -89.027) (xy 17.145 -89.535) (xy 16.764 -89.535) (xy 16.764 -89.027)
				)
			)
		)
	)
	(footprint ""
		(layer "B.Cu")
		(at 435.434994 -42.0116 -90)
		(property "Reference" "C25W5"
			(at 0.8382 -0.67818 270)
			(unlocked yes)
			(layer "B.SilkS")
			(effects
				(font
					(size 0.4064 0.254)
					(thickness 0.1524)
				)
				(justify left mirror)
			)
		)
		(property "Value" ""
			(at 0 0 90)
			(layer "B.Fab")
			(effects
				(font
					(size 1.27 1.27)
				)
				(justify mirror)
			)
		)
		(duplicate_pad_numbers_are_jumpers no)
		(fp_poly
			(pts
				(xy -0.3048 -0.1016) (xy -0.3048 0.9906) (xy 0.3048 0.9906) (xy 0.3048 -0.1016)
			)
			(stroke
				(width 0)
				(type default)
			)
			(fill no)
			(layer "B.CrtYd")
		)
		(fp_line
			(start -0.3048 0.9906)
			(end -0.3048 -0.1016)
			(stroke
				(width 0.1)
				(type default)
			)
			(layer "B.Fab")
		)
		(fp_line
			(start 0.3048 0.9906)
			(end -0.3048 0.9906)
			(stroke
				(width 0.1)
				(type default)
			)
			(layer "B.Fab")
		)
		(fp_line
			(start -0.3048 -0.1016)
			(end 0.3048 -0.1016)
			(stroke
				(width 0.1)
				(type default)
			)
			(layer "B.Fab")
		)
		(fp_line
			(start 0.3048 -0.1016)
			(end 0.3048 0.9906)
			(stroke
				(width 0.1)
				(type default)
			)
			(layer "B.Fab")
		)
		(pad "1" smd rect
			(at 0 0 90)
			(size 0.508 0.508)
			(layers "B.Cu" "B.Mask" "B.Paste")
			(net "P1V2_AUX_BMC")
		)
		(pad "2" smd rect
			(at 0 0.889 90)
			(size 0.508 0.508)
			(layers "B.Cu" "B.Mask" "B.Paste")
			(net "GND")
		)
		(zone
			(layer "B.Cu")
			(hatch none 0.5)
			(connect_pads
				(clearance 0)
			)
			(min_thickness 0.25)
			(keepout
				(tracks not_allowed)
				(vias allowed)
				(pads allowed)
				(copperpour not_allowed)
				(footprints allowed)
			)
			(placement
				(enabled no)
				(sheetname "")
			)
			(fill
				(thermal_gap 0.5)
				(thermal_bridge_width 0.5)
				(island_removal_mode 0)
			)
			(polygon
				(pts
					(xy 434.799994 -41.7576) (xy 434.799994 -42.2656) (xy 435.180994 -42.2656) (xy 435.180994 -41.7576)
				)
			)
		)
		(zone
			(layer "B.Cu")
			(hatch none 0.5)
			(connect_pads
				(clearance 0)
			)
			(min_thickness 0.25)
			(keepout
				(tracks allowed)
				(vias not_allowed)
				(pads allowed)
				(copperpour not_allowed)
				(footprints allowed)
			)
			(placement
				(enabled no)
				(sheetname "")
			)
			(fill
				(thermal_gap 0.5)
				(thermal_bridge_width 0.5)
				(island_removal_mode 0)
			)
			(polygon
				(pts
					(xy 435.180994 -41.7576) (xy 435.180994 -42.2656) (xy 434.799994 -42.2656) (xy 434.799994 -41.7576)
				)
			)
		)
	)
	(footprint ""
		(layer "B.Cu")
		(at 13.921232 3.752342 90)
		(property "Reference" "R9U8"
			(at 0 0 90)
			(layer "B.SilkS")
			(hide yes)
			(effects
				(font
					(size 1.27 1.27)
				)
				(justify mirror)
			)
		)
		(property "Value" ""
			(at 0 0 90)
			(layer "B.Fab")
			(effects
				(font
					(size 1.27 1.27)
				)
				(justify mirror)
			)
		)
		(duplicate_pad_numbers_are_jumpers no)
		(fp_poly
			(pts
				(xy 0.2794 -0.1016) (xy -0.2794 -0.1016) (xy -0.2794 0.9906) (xy 0.2794 0.9906)
			)
			(stroke
				(width 0)
				(type default)
			)
			(fill no)
			(layer "B.CrtYd")
		)
		(fp_line
			(start 0.2794 -0.1016)
			(end 0.2794 0.9906)
			(stroke
				(width 0.1)
				(type default)
			)
			(layer "B.Fab")
		)
		(fp_line
			(start -0.2794 -0.1016)
			(end 0.2794 -0.1016)
			(stroke
				(width 0.1)
				(type default)
			)
			(layer "B.Fab")
		)
		(fp_line
			(start 0.2794 0.9906)
			(end -0.2794 0.9906)
			(stroke
				(width 0.1)
				(type default)
			)
			(layer "B.Fab")
		)
		(fp_line
			(start -0.2794 0.9906)
			(end -0.2794 -0.1016)
			(stroke
				(width 0.1)
				(type default)
			)
			(layer "B.Fab")
		)
		(pad "1" smd rect
			(at 0 0 270)
			(size 0.508 0.508)
			(layers "B.Cu" "B.Mask" "B.Paste")
			(net "P3V3_STBY")
		)
		(pad "2" smd rect
			(at 0 0.889 270)
			(size 0.508 0.508)
			(layers "B.Cu" "B.Mask" "B.Paste")
			(net "VR_PVDDQ_GHJ_VREN")
		)
		(zone
			(layer "B.Cu")
			(hatch none 0.5)
			(connect_pads
				(clearance 0)
			)
			(min_thickness 0.25)
			(keepout
				(tracks allowed)
				(vias not_allowed)
				(pads allowed)
				(copperpour not_allowed)
				(footprints allowed)
			)
			(placement
				(enabled no)
				(sheetname "")
			)
			(fill
				(thermal_gap 0.5)
				(thermal_bridge_width 0.5)
				(island_removal_mode 0)
			)
			(polygon
				(pts
					(xy 14.175232 3.498342) (xy 14.175232 4.006342) (xy 14.556232 4.006342) (xy 14.556232 3.498342)
				)
			)
		)
		(zone
			(layer "B.Cu")
			(hatch none 0.5)
			(connect_pads
				(clearance 0)
			)
			(min_thickness 0.25)
			(keepout
				(tracks not_allowed)
				(vias allowed)
				(pads allowed)
				(copperpour not_allowed)
				(footprints allowed)
			)
			(placement
				(enabled no)
				(sheetname "")
			)
			(fill
				(thermal_gap 0.5)
				(thermal_bridge_width 0.5)
				(island_removal_mode 0)
			)
			(polygon
				(pts
					(xy 14.556232 3.498342) (xy 14.556232 4.006342) (xy 14.175232 4.006342) (xy 14.175232 3.498342)
				)
			)
		)
	)
)
